(kicad_pcb
	(version 20260206)
	(generator "pcbnew")
	(generator_version "10.0")
	(general
		(thickness 1.6)
		(legacy_teardrops no)
	)
	(paper "A4")
	(title_block
		(title "01162023_DA0F0TEBIF0_F0T_Expander_BD_F_brd_V02_OCP.brd")
		(comment 1 "Grand Teton / footprints 4181-4186 of 9728")
	)
	(layers
		(0 "F.Cu" signal "TOP")
		(4 "In1.Cu" signal "GND")
		(6 "In2.Cu" signal "VCC")
		(8 "In3.Cu" signal "VCC1")
		(10 "In4.Cu" signal "GND1")
		(12 "In5.Cu" signal "IN1")
		(14 "In6.Cu" signal "GND2")
		(16 "In7.Cu" signal "IN2")
		(18 "In8.Cu" signal "GND3")
		(20 "In9.Cu" signal "IN3")
		(22 "In10.Cu" signal "GND4")
		(24 "In11.Cu" signal "IN4")
		(26 "In12.Cu" signal "GND5")
		(28 "In13.Cu" signal "IN5")
		(30 "In14.Cu" signal "GND6")
		(32 "In15.Cu" signal "IN6")
		(34 "In16.Cu" signal "GND7")
		(2 "B.Cu" signal "BOTTOM")
		(9 "F.Adhes" user "F.Adhesive")
		(11 "B.Adhes" user "B.Adhesive")
		(13 "F.Paste" user "Package Geometry/Pastemask Top")
		(15 "B.Paste" user "Package Geometry/Pastemask Bottom")
		(5 "F.SilkS" user "Ref Des/Silkscreen Top")
		(7 "B.SilkS" user "Ref Des/Silkscreen Bottom")
		(1 "F.Mask" user "Board Geometry/Soldermask Top")
		(3 "B.Mask" user "Board Geometry/Soldermask Bottom")
		(17 "Dwgs.User" user "User.Drawings")
		(19 "Cmts.User" user "User.Comments")
		(21 "Eco1.User" user "User.Eco1")
		(23 "Eco2.User" user "User.Eco2")
		(25 "Edge.Cuts" user "Board Geometry/Outline")
		(27 "Margin" user)
		(31 "F.CrtYd" user "Package Geometry/Place Bound Top")
		(29 "B.CrtYd" user "Package Geometry/Place Bound Bottom")
		(35 "F.Fab" user "Ref Des/Assembly Top")
		(33 "B.Fab" user "Ref Des/Assembly Bottom")
	)
	(footprint ""
		(layer "F.Cu")
		(at 262.281924 -292.991032 180)
		(property "Reference" "C3380"
			(at 0 0 180)
			(layer "F.SilkS")
			(hide yes)
			(effects
				(font
					(size 1.27 1.27)
				)
			)
		)
		(property "Value" ""
			(at 0 0 180)
			(layer "F.Fab")
			(effects
				(font
					(size 1.27 1.27)
				)
			)
		)
		(duplicate_pad_numbers_are_jumpers no)
		(fp_line
			(start 1.2954 0.5842)
			(end -1.2954 0.5842)
			(stroke
				(width 0.1524)
				(type default)
			)
			(layer "F.SilkS")
		)
		(fp_line
			(start 1.2954 -0.5842)
			(end 1.2954 0.5842)
			(stroke
				(width 0.1524)
				(type default)
			)
			(layer "F.SilkS")
		)
		(fp_line
			(start -1.2954 0.5842)
			(end -1.2954 -0.5842)
			(stroke
				(width 0.1524)
				(type default)
			)
			(layer "F.SilkS")
		)
		(fp_line
			(start -1.2954 -0.5842)
			(end 1.2954 -0.5842)
			(stroke
				(width 0.1524)
				(type default)
			)
			(layer "F.SilkS")
		)
		(fp_line
			(start 1.1938 0.4064)
			(end 0.8636 0.4064)
			(stroke
				(width 0.1)
				(type default)
			)
			(layer "F.Fab")
		)
		(fp_line
			(start 1.1938 -0.4064)
			(end 1.1938 0.4064)
			(stroke
				(width 0.1)
				(type default)
			)
			(layer "F.Fab")
		)
		(fp_line
			(start 0.8636 0.4572)
			(end -0.8636 0.4572)
			(stroke
				(width 0.1)
				(type default)
			)
			(layer "F.Fab")
		)
		(fp_line
			(start 0.8636 0.4064)
			(end 0.8636 0.4572)
			(stroke
				(width 0.1)
				(type default)
			)
			(layer "F.Fab")
		)
		(fp_line
			(start 0.8636 -0.4064)
			(end 1.1938 -0.4064)
			(stroke
				(width 0.1)
				(type default)
			)
			(layer "F.Fab")
		)
		(fp_line
			(start 0.8636 -0.4572)
			(end 0.8636 -0.4064)
			(stroke
				(width 0.1)
				(type default)
			)
			(layer "F.Fab")
		)
		(fp_line
			(start -0.8636 0.4572)
			(end -0.8636 0.4064)
			(stroke
				(width 0.1)
				(type default)
			)
			(layer "F.Fab")
		)
		(fp_line
			(start -0.8636 0.4064)
			(end -1.1938 0.4064)
			(stroke
				(width 0.1)
				(type default)
			)
			(layer "F.Fab")
		)
		(fp_line
			(start -0.8636 -0.4064)
			(end -0.8636 -0.4572)
			(stroke
				(width 0.1)
				(type default)
			)
			(layer "F.Fab")
		)
		(fp_line
			(start -0.8636 -0.4572)
			(end 0.8636 -0.4572)
			(stroke
				(width 0.1)
				(type default)
			)
			(layer "F.Fab")
		)
		(fp_line
			(start -1.1938 0.4064)
			(end -1.1938 -0.4064)
			(stroke
				(width 0.1)
				(type default)
			)
			(layer "F.Fab")
		)
		(fp_line
			(start -1.1938 -0.4064)
			(end -0.8636 -0.4064)
			(stroke
				(width 0.1)
				(type default)
			)
			(layer "F.Fab")
		)
		(pad "1" smd rect
			(at -0.7366 0 90)
			(size 0.7112 0.8128)
			(layers "F.Cu" "F.Mask" "F.Paste")
			(net "PCEPLL2_VDDA18_PEX2_R")
		)
		(pad "2" smd rect
			(at 0.7366 0 90)
			(size 0.7112 0.8128)
			(layers "F.Cu" "F.Mask" "F.Paste")
			(net "GND")
		)
	)
	(footprint ""
		(layer "F.Cu")
		(at 89.933018 -311.946544 135)
		(property "Reference" "R1235"
			(at 0 0 135)
			(layer "F.SilkS")
			(hide yes)
			(effects
				(font
					(size 1.27 1.27)
				)
			)
		)
		(property "Value" ""
			(at 0 0 135)
			(layer "F.Fab")
			(effects
				(font
					(size 1.27 1.27)
				)
			)
		)
		(duplicate_pad_numbers_are_jumpers no)
		(fp_line
			(start 0.787389 -0.406267)
			(end 0.787389 0.406267)
			(stroke
				(width 0.1524)
				(type default)
			)
			(layer "F.SilkS")
		)
		(fp_line
			(start 0.787389 0.406267)
			(end -0.787389 0.406267)
			(stroke
				(width 0.1524)
				(type default)
			)
			(layer "F.SilkS")
		)
		(fp_line
			(start -0.787389 -0.406267)
			(end 0.787389 -0.406267)
			(stroke
				(width 0.1524)
				(type default)
			)
			(layer "F.SilkS")
		)
		(fp_line
			(start -0.787389 0.406267)
			(end -0.787389 -0.406267)
			(stroke
				(width 0.1524)
				(type default)
			)
			(layer "F.SilkS")
		)
		(fp_line
			(start 0.679446 -0.30479)
			(end 0.679446 0.30479)
			(stroke
				(width 0.1)
				(type default)
			)
			(layer "F.Fab")
		)
		(fp_line
			(start 0.120515 -0.30479)
			(end 0.679446 -0.30479)
			(stroke
				(width 0.1)
				(type default)
			)
			(layer "F.Fab")
		)
		(fp_line
			(start 0.120695 -0.279466)
			(end 0.120515 -0.30479)
			(stroke
				(width 0.1)
				(type default)
			)
			(layer "F.Fab")
		)
		(fp_line
			(start 0.679446 0.30479)
			(end 0.120515 0.30479)
			(stroke
				(width 0.1)
				(type default)
			)
			(layer "F.Fab")
		)
		(fp_line
			(start -0.120695 -0.304969)
			(end -0.120695 -0.279466)
			(stroke
				(width 0.1)
				(type default)
			)
			(layer "F.Fab")
		)
		(fp_line
			(start -0.120695 -0.279466)
			(end 0.120695 -0.279466)
			(stroke
				(width 0.1)
				(type default)
			)
			(layer "F.Fab")
		)
		(fp_line
			(start 0.120335 0.279466)
			(end -0.120695 0.279466)
			(stroke
				(width 0.1)
				(type default)
			)
			(layer "F.Fab")
		)
		(fp_line
			(start 0.120515 0.30479)
			(end 0.120335 0.279466)
			(stroke
				(width 0.1)
				(type default)
			)
			(layer "F.Fab")
		)
		(fp_line
			(start -0.679446 -0.305149)
			(end -0.120695 -0.304969)
			(stroke
				(width 0.1)
				(type default)
			)
			(layer "F.Fab")
		)
		(fp_line
			(start -0.120695 0.279466)
			(end -0.120515 0.30479)
			(stroke
				(width 0.1)
				(type default)
			)
			(layer "F.Fab")
		)
		(fp_line
			(start -0.120515 0.30479)
			(end -0.679446 0.30479)
			(stroke
				(width 0.1)
				(type default)
			)
			(layer "F.Fab")
		)
		(fp_line
			(start -0.679446 0.30479)
			(end -0.679446 -0.305149)
			(stroke
				(width 0.1)
				(type default)
			)
			(layer "F.Fab")
		)
		(pad "1" smd circle
			(at -0.40005 0 135)
			(size 0 0)
			(layers "F.Cu" "F.Mask" "F.Paste")
			(net "PEX0_SPARE5")
		)
		(pad "2" smd circle
			(at 0.40005 0 135)
			(size 0 0)
			(layers "F.Cu" "F.Mask" "F.Paste")
			(net "P1V8_PEX")
		)
	)
	(footprint ""
		(layer "F.Cu")
		(at 410.791914 -161.881566 90)
		(property "Reference" "Q122"
			(at 0.018034 -1.901444 90)
			(unlocked yes)
			(layer "F.SilkS")
			(effects
				(font
					(size 0.7874 0.5842)
					(thickness 0.1524)
				)
			)
		)
		(property "Value" ""
			(at 0 0 90)
			(layer "F.Fab")
			(effects
				(font
					(size 1.27 1.27)
				)
			)
		)
		(duplicate_pad_numbers_are_jumpers no)
		(fp_line
			(start 1.376172 -1.199896)
			(end 1.376172 1.199896)
			(stroke
				(width 0.1524)
				(type default)
			)
			(layer "F.SilkS")
		)
		(fp_line
			(start 0.508 -1.199896)
			(end 1.376172 -1.199896)
			(stroke
				(width 0.1524)
				(type default)
			)
			(layer "F.SilkS")
		)
		(fp_line
			(start -0.508 -1.199896)
			(end 0 -0.762)
			(stroke
				(width 0.1524)
				(type default)
			)
			(layer "F.SilkS")
		)
		(fp_line
			(start -1.376172 -1.199896)
			(end -0.508 -1.199896)
			(stroke
				(width 0.1524)
				(type default)
			)
			(layer "F.SilkS")
		)
		(fp_line
			(start 0 -0.762)
			(end 0.508 -1.199896)
			(stroke
				(width 0.1524)
				(type default)
			)
			(layer "F.SilkS")
		)
		(fp_line
			(start 1.376172 1.199896)
			(end -1.376172 1.199896)
			(stroke
				(width 0.1524)
				(type default)
			)
			(layer "F.SilkS")
		)
		(fp_line
			(start -1.376172 1.199896)
			(end -1.376172 -1.199896)
			(stroke
				(width 0.1524)
				(type default)
			)
			(layer "F.SilkS")
		)
		(fp_poly
			(pts
				(xy -1.531874 -1.143762) (xy -1.801368 -1.95199) (xy -2.340102 -1.413256)
			)
			(stroke
				(width 0)
				(type default)
			)
			(fill yes)
			(layer "F.SilkS")
		)
		(fp_line
			(start 0.674878 -1.100074)
			(end 0.674878 1.100074)
			(stroke
				(width 0.1)
				(type default)
			)
			(layer "F.Fab")
		)
		(fp_line
			(start -0.674878 -1.100074)
			(end 0.674878 -1.100074)
			(stroke
				(width 0.1)
				(type default)
			)
			(layer "F.Fab")
		)
		(fp_line
			(start 0.674878 1.100074)
			(end -0.674878 1.100074)
			(stroke
				(width 0.1)
				(type default)
			)
			(layer "F.Fab")
		)
		(fp_line
			(start -0.674878 1.100074)
			(end -0.674878 -1.100074)
			(stroke
				(width 0.1)
				(type default)
			)
			(layer "F.Fab")
		)
		(fp_poly
			(pts
				(xy -1.4605 -0.7493) (xy -2.2225 -1.1303) (xy -2.2225 -0.3683)
			)
			(stroke
				(width 0)
				(type default)
			)
			(fill yes)
			(layer "F.Fab")
		)
		(pad "1" smd rect
			(at -0.899922 -0.750062)
			(size 0.6096 0.6096)
			(layers "F.Cu" "F.Mask" "F.Paste")
			(net "GND")
		)
		(pad "2" smd rect
			(at -0.899922 0)
			(size 0.4064 0.6096)
			(layers "F.Cu" "F.Mask" "F.Paste")
			(net "FM_SYS_THROTTLE_NIC6")
		)
		(pad "3" smd rect
			(at -0.899922 0.750062)
			(size 0.6096 0.6096)
			(layers "F.Cu" "F.Mask" "F.Paste")
			(net "NIC7_PWRBRK_N")
		)
		(pad "4" smd rect
			(at 0.899922 0.750062)
			(size 0.6096 0.6096)
			(layers "F.Cu" "F.Mask" "F.Paste")
			(net "GND")
		)
		(pad "5" smd rect
			(at 0.899922 0)
			(size 0.4064 0.6096)
			(layers "F.Cu" "F.Mask" "F.Paste")
			(net "FM_SYS_THROTTLE_NIC7")
		)
		(pad "6" smd rect
			(at 0.899922 -0.750062)
			(size 0.6096 0.6096)
			(layers "F.Cu" "F.Mask" "F.Paste")
			(net "NIC6_PWRBRK_N")
		)
	)
	(footprint ""
		(layer "F.Cu")
		(at 117.706902 -285.088584 90)
		(property "Reference" "PC57"
			(at 0 0 90)
			(layer "F.SilkS")
			(hide yes)
			(effects
				(font
					(size 1.27 1.27)
				)
			)
		)
		(property "Value" ""
			(at 0 0 90)
			(layer "F.Fab")
			(effects
				(font
					(size 1.27 1.27)
				)
			)
		)
		(duplicate_pad_numbers_are_jumpers no)
		(fp_line
			(start 0.7874 -0.4064)
			(end 0.7874 0.4064)
			(stroke
				(width 0.1524)
				(type default)
			)
			(layer "F.SilkS")
		)
		(fp_line
			(start -0.7874 -0.4064)
			(end 0.7874 -0.4064)
			(stroke
				(width 0.1524)
				(type default)
			)
			(layer "F.SilkS")
		)
		(fp_line
			(start 0.7874 0.4064)
			(end -0.7874 0.4064)
			(stroke
				(width 0.1524)
				(type default)
			)
			(layer "F.SilkS")
		)
		(fp_line
			(start -0.7874 0.4064)
			(end -0.7874 -0.4064)
			(stroke
				(width 0.1524)
				(type default)
			)
			(layer "F.SilkS")
		)
		(fp_line
			(start -0.12065 -0.305054)
			(end -0.12065 -0.2794)
			(stroke
				(width 0.1)
				(type default)
			)
			(layer "F.Fab")
		)
		(fp_line
			(start -0.67945 -0.305054)
			(end -0.12065 -0.305054)
			(stroke
				(width 0.1)
				(type default)
			)
			(layer "F.Fab")
		)
		(fp_line
			(start 0.67945 -0.3048)
			(end 0.67945 0.3048)
			(stroke
				(width 0.1)
				(type default)
			)
			(layer "F.Fab")
		)
		(fp_line
			(start 0.12065 -0.3048)
			(end 0.67945 -0.3048)
			(stroke
				(width 0.1)
				(type default)
			)
			(layer "F.Fab")
		)
		(fp_line
			(start 0.12065 -0.2794)
			(end 0.12065 -0.3048)
			(stroke
				(width 0.1)
				(type default)
			)
			(layer "F.Fab")
		)
		(fp_line
			(start -0.12065 -0.2794)
			(end 0.12065 -0.2794)
			(stroke
				(width 0.1)
				(type default)
			)
			(layer "F.Fab")
		)
		(fp_line
			(start 0.120396 0.2794)
			(end -0.12065 0.2794)
			(stroke
				(width 0.1)
				(type default)
			)
			(layer "F.Fab")
		)
		(fp_line
			(start -0.12065 0.2794)
			(end -0.12065 0.3048)
			(stroke
				(width 0.1)
				(type default)
			)
			(layer "F.Fab")
		)
		(fp_line
			(start 0.67945 0.3048)
			(end 0.120396 0.3048)
			(stroke
				(width 0.1)
				(type default)
			)
			(layer "F.Fab")
		)
		(fp_line
			(start 0.120396 0.3048)
			(end 0.120396 0.2794)
			(stroke
				(width 0.1)
				(type default)
			)
			(layer "F.Fab")
		)
		(fp_line
			(start -0.12065 0.3048)
			(end -0.67945 0.3048)
			(stroke
				(width 0.1)
				(type default)
			)
			(layer "F.Fab")
		)
		(fp_line
			(start -0.67945 0.3048)
			(end -0.67945 -0.305054)
			(stroke
				(width 0.1)
				(type default)
			)
			(layer "F.Fab")
		)
		(pad "1" smd circle
			(at -0.40005 0 90)
			(size 0 0)
			(layers "F.Cu" "F.Mask" "F.Paste")
			(net "P0V8_PEX0_PVCC")
		)
		(pad "2" smd circle
			(at 0.40005 0 90)
			(size 0 0)
			(layers "F.Cu" "F.Mask" "F.Paste")
			(net "GND")
		)
	)
	(footprint ""
		(layer "F.Cu")
		(at 357.19131 -252.416564 90)
		(property "Reference" "R836"
			(at 0 0 90)
			(layer "F.SilkS")
			(hide yes)
			(effects
				(font
					(size 1.27 1.27)
				)
			)
		)
		(property "Value" ""
			(at 0 0 90)
			(layer "F.Fab")
			(effects
				(font
					(size 1.27 1.27)
				)
			)
		)
		(duplicate_pad_numbers_are_jumpers no)
		(fp_line
			(start 0.7874 -0.4064)
			(end 0.7874 0.4064)
			(stroke
				(width 0.1524)
				(type default)
			)
			(layer "F.SilkS")
		)
		(fp_line
			(start -0.7874 -0.4064)
			(end 0.7874 -0.4064)
			(stroke
				(width 0.1524)
				(type default)
			)
			(layer "F.SilkS")
		)
		(fp_line
			(start 0.7874 0.4064)
			(end -0.7874 0.4064)
			(stroke
				(width 0.1524)
				(type default)
			)
			(layer "F.SilkS")
		)
		(fp_line
			(start -0.7874 0.4064)
			(end -0.7874 -0.4064)
			(stroke
				(width 0.1524)
				(type default)
			)
			(layer "F.SilkS")
		)
		(fp_line
			(start -0.12065 -0.305054)
			(end -0.12065 -0.2794)
			(stroke
				(width 0.1)
				(type default)
			)
			(layer "F.Fab")
		)
		(fp_line
			(start -0.67945 -0.305054)
			(end -0.12065 -0.305054)
			(stroke
				(width 0.1)
				(type default)
			)
			(layer "F.Fab")
		)
		(fp_line
			(start 0.67945 -0.3048)
			(end 0.67945 0.3048)
			(stroke
				(width 0.1)
				(type default)
			)
			(layer "F.Fab")
		)
		(fp_line
			(start 0.12065 -0.3048)
			(end 0.67945 -0.3048)
			(stroke
				(width 0.1)
				(type default)
			)
			(layer "F.Fab")
		)
		(fp_line
			(start 0.12065 -0.2794)
			(end 0.12065 -0.3048)
			(stroke
				(width 0.1)
				(type default)
			)
			(layer "F.Fab")
		)
		(fp_line
			(start -0.12065 -0.2794)
			(end 0.12065 -0.2794)
			(stroke
				(width 0.1)
				(type default)
			)
			(layer "F.Fab")
		)
		(fp_line
			(start 0.120396 0.2794)
			(end -0.12065 0.2794)
			(stroke
				(width 0.1)
				(type default)
			)
			(layer "F.Fab")
		)
		(fp_line
			(start -0.12065 0.2794)
			(end -0.12065 0.3048)
			(stroke
				(width 0.1)
				(type default)
			)
			(layer "F.Fab")
		)
		(fp_line
			(start 0.67945 0.3048)
			(end 0.120396 0.3048)
			(stroke
				(width 0.1)
				(type default)
			)
			(layer "F.Fab")
		)
		(fp_line
			(start 0.120396 0.3048)
			(end 0.120396 0.2794)
			(stroke
				(width 0.1)
				(type default)
			)
			(layer "F.Fab")
		)
		(fp_line
			(start -0.12065 0.3048)
			(end -0.67945 0.3048)
			(stroke
				(width 0.1)
				(type default)
			)
			(layer "F.Fab")
		)
		(fp_line
			(start -0.67945 0.3048)
			(end -0.67945 -0.305054)
			(stroke
				(width 0.1)
				(type default)
			)
			(layer "F.Fab")
		)
		(pad "1" smd circle
			(at -0.40005 0 90)
			(size 0 0)
			(layers "F.Cu" "F.Mask" "F.Paste")
			(net "SMB_BIC_I2C6_MUX_VR_R_SCL")
		)
		(pad "2" smd circle
			(at 0.40005 0 90)
			(size 0 0)
			(layers "F.Cu" "F.Mask" "F.Paste")
			(net "SMB_VR_P0V8_PEX2_SCL")
		)
	)
	(footprint ""
		(layer "F.Cu")
		(at 446.038478 -44.341542 90)
		(property "Reference" "C408"
			(at 0 0 90)
			(layer "F.SilkS")
			(hide yes)
			(effects
				(font
					(size 1.27 1.27)
				)
			)
		)
		(property "Value" ""
			(at 0 0 90)
			(layer "F.Fab")
			(effects
				(font
					(size 1.27 1.27)
				)
			)
		)
		(duplicate_pad_numbers_are_jumpers no)
		(fp_line
			(start 0.7874 -0.4064)
			(end 0.7874 0.4064)
			(stroke
				(width 0.1524)
				(type default)
			)
			(layer "F.SilkS")
		)
		(fp_line
			(start -0.7874 -0.4064)
			(end 0.7874 -0.4064)
			(stroke
				(width 0.1524)
				(type default)
			)
			(layer "F.SilkS")
		)
		(fp_line
			(start 0.7874 0.4064)
			(end -0.7874 0.4064)
			(stroke
				(width 0.1524)
				(type default)
			)
			(layer "F.SilkS")
		)
		(fp_line
			(start -0.7874 0.4064)
			(end -0.7874 -0.4064)
			(stroke
				(width 0.1524)
				(type default)
			)
			(layer "F.SilkS")
		)
		(fp_line
			(start -0.12065 -0.305054)
			(end -0.12065 -0.2794)
			(stroke
				(width 0.1)
				(type default)
			)
			(layer "F.Fab")
		)
		(fp_line
			(start -0.67945 -0.305054)
			(end -0.12065 -0.305054)
			(stroke
				(width 0.1)
				(type default)
			)
			(layer "F.Fab")
		)
		(fp_line
			(start 0.67945 -0.3048)
			(end 0.67945 0.3048)
			(stroke
				(width 0.1)
				(type default)
			)
			(layer "F.Fab")
		)
		(fp_line
			(start 0.12065 -0.3048)
			(end 0.67945 -0.3048)
			(stroke
				(width 0.1)
				(type default)
			)
			(layer "F.Fab")
		)
		(fp_line
			(start 0.12065 -0.2794)
			(end 0.12065 -0.3048)
			(stroke
				(width 0.1)
				(type default)
			)
			(layer "F.Fab")
		)
		(fp_line
			(start -0.12065 -0.2794)
			(end 0.12065 -0.2794)
			(stroke
				(width 0.1)
				(type default)
			)
			(layer "F.Fab")
		)
		(fp_line
			(start 0.120396 0.2794)
			(end -0.12065 0.2794)
			(stroke
				(width 0.1)
				(type default)
			)
			(layer "F.Fab")
		)
		(fp_line
			(start -0.12065 0.2794)
			(end -0.12065 0.3048)
			(stroke
				(width 0.1)
				(type default)
			)
			(layer "F.Fab")
		)
		(fp_line
			(start 0.67945 0.3048)
			(end 0.120396 0.3048)
			(stroke
				(width 0.1)
				(type default)
			)
			(layer "F.Fab")
		)
		(fp_line
			(start 0.120396 0.3048)
			(end 0.120396 0.2794)
			(stroke
				(width 0.1)
				(type default)
			)
			(layer "F.Fab")
		)
		(fp_line
			(start -0.12065 0.3048)
			(end -0.67945 0.3048)
			(stroke
				(width 0.1)
				(type default)
			)
			(layer "F.Fab")
		)
		(fp_line
			(start -0.67945 0.3048)
			(end -0.67945 -0.305054)
			(stroke
				(width 0.1)
				(type default)
			)
			(layer "F.Fab")
		)
		(pad "1" smd circle
			(at -0.40005 0 90)
			(size 0 0)
			(layers "F.Cu" "F.Mask" "F.Paste")
			(net "P12V_SSD15_VIN_P")
		)
		(pad "2" smd circle
			(at 0.40005 0 90)
			(size 0 0)
			(layers "F.Cu" "F.Mask" "F.Paste")
			(net "P12V_SSD15_VIN_N")
		)
	)
)
